(kicad_pcb
	(version 20260206)
	(generator "pcbnew")
	(generator_version "10.0")
	(general
		(thickness 1.6)
		(legacy_teardrops no)
	)
	(paper "A4")
	(title_block
		(title "v1-pdb — T6M_PDB_D_0927_0900.brd")
		(comment 1 "Open CloudServer (Microsoft) / footprints 225-234 of 321")
	)
	(layers
		(0 "F.Cu" signal "TOP")
		(4 "In1.Cu" signal "GND")
		(6 "In2.Cu" signal "IN1")
		(8 "In3.Cu" signal "VCC")
		(10 "In4.Cu" signal "VCC1")
		(12 "In5.Cu" signal "IN2")
		(14 "In6.Cu" signal "GND1")
		(2 "B.Cu" signal "BOTTOM")
		(9 "F.Adhes" user "F.Adhesive")
		(11 "B.Adhes" user "B.Adhesive")
		(13 "F.Paste" user "Package Geometry/Pastemask Top")
		(15 "B.Paste" user "Package Geometry/Pastemask Bottom")
		(5 "F.SilkS" user "Ref Des/Silkscreen Top")
		(7 "B.SilkS" user "Ref Des/Silkscreen Bottom")
		(1 "F.Mask" user "Board Geometry/Soldermask Top")
		(3 "B.Mask" user "Board Geometry/Soldermask Bottom")
		(17 "Dwgs.User" user "User.Drawings")
		(19 "Cmts.User" user "User.Comments")
		(21 "Eco1.User" user "User.Eco1")
		(23 "Eco2.User" user "User.Eco2")
		(25 "Edge.Cuts" user "Board Geometry/Outline")
		(27 "Margin" user)
		(31 "F.CrtYd" user "Package Geometry/Place Bound Top")
		(29 "B.CrtYd" user "Package Geometry/Place Bound Bottom")
		(35 "F.Fab" user "Ref Des/Assembly Top")
		(33 "B.Fab" user "Ref Des/Assembly Bottom")
	)
	(footprint ""
		(layer "F.Cu")
		(at 18.264886 -330.45527 -90)
		(property "Reference" "R36"
			(at 3.685032 -0.234188 90)
			(unlocked yes)
			(layer "F.SilkS")
			(effects
				(font
					(size 0.7874 0.5842)
					(thickness 0.1524)
				)
				(justify left)
			)
		)
		(property "Value" ""
			(at 0 0 270)
			(layer "F.Fab")
			(effects
				(font
					(size 1.27 1.27)
				)
			)
		)
		(duplicate_pad_numbers_are_jumpers no)
		(fp_line
			(start -0.7874 0.4064)
			(end -0.7874 -0.4064)
			(stroke
				(width 0.1524)
				(type default)
			)
			(layer "F.SilkS")
		)
		(fp_line
			(start 0.7874 0.4064)
			(end -0.7874 0.4064)
			(stroke
				(width 0.1524)
				(type default)
			)
			(layer "F.SilkS")
		)
		(fp_line
			(start -0.7874 -0.4064)
			(end 0.7874 -0.4064)
			(stroke
				(width 0.1524)
				(type default)
			)
			(layer "F.SilkS")
		)
		(fp_line
			(start 0.7874 -0.4064)
			(end 0.7874 0.4064)
			(stroke
				(width 0.1524)
				(type default)
			)
			(layer "F.SilkS")
		)
		(fp_poly
			(pts
				(xy -0.508 0.2794) (xy -0.508 0.2286) (xy -0.635 0.2286) (xy -0.635 -0.254) (xy -0.5334 -0.254)
				(xy -0.5334 -0.2794) (xy 0.5334 -0.2794) (xy 0.5334 -0.254) (xy 0.635 -0.254) (xy 0.635 0.254) (xy 0.5334 0.254)
				(xy 0.5334 0.2794)
			)
			(stroke
				(width 0)
				(type default)
			)
			(fill no)
			(layer "F.CrtYd")
		)
		(pad "1" smd rect
			(at 0.40005 0 270)
			(size 0.4572 0.508)
			(layers "F.Cu" "F.Mask" "F.Paste")
			(net "P3V3")
		)
		(pad "2" smd rect
			(at -0.40005 0 270)
			(size 0.4572 0.508)
			(layers "F.Cu" "F.Mask" "F.Paste")
			(net "FRU_A2")
		)
	)
	(footprint ""
		(layer "F.Cu")
		(at 39.85641 -103.52405 180)
		(property "Reference" "R11"
			(at -1.627124 0.025908 0)
			(unlocked yes)
			(layer "F.SilkS")
			(effects
				(font
					(size 0.7874 0.5842)
					(thickness 0.1524)
				)
				(justify left)
			)
		)
		(property "Value" ""
			(at 0 0 180)
			(layer "F.Fab")
			(effects
				(font
					(size 1.27 1.27)
				)
			)
		)
		(duplicate_pad_numbers_are_jumpers no)
		(fp_line
			(start 0.7874 0.4064)
			(end -0.7874 0.4064)
			(stroke
				(width 0.1524)
				(type default)
			)
			(layer "F.SilkS")
		)
		(fp_line
			(start 0.7874 -0.4064)
			(end 0.7874 0.4064)
			(stroke
				(width 0.1524)
				(type default)
			)
			(layer "F.SilkS")
		)
		(fp_line
			(start -0.7874 0.4064)
			(end -0.7874 -0.4064)
			(stroke
				(width 0.1524)
				(type default)
			)
			(layer "F.SilkS")
		)
		(fp_line
			(start -0.7874 -0.4064)
			(end 0.7874 -0.4064)
			(stroke
				(width 0.1524)
				(type default)
			)
			(layer "F.SilkS")
		)
		(fp_poly
			(pts
				(xy -0.508 0.2794) (xy -0.508 0.2286) (xy -0.635 0.2286) (xy -0.635 -0.254) (xy -0.5334 -0.254)
				(xy -0.5334 -0.2794) (xy 0.5334 -0.2794) (xy 0.5334 -0.254) (xy 0.635 -0.254) (xy 0.635 0.254) (xy 0.5334 0.254)
				(xy 0.5334 0.2794)
			)
			(stroke
				(width 0)
				(type default)
			)
			(fill no)
			(layer "F.CrtYd")
		)
		(pad "1" smd rect
			(at 0.40005 0 180)
			(size 0.4572 0.508)
			(layers "F.Cu" "F.Mask" "F.Paste")
			(net "PSU2_RETURN")
		)
		(pad "2" smd rect
			(at -0.40005 0 180)
			(size 0.4572 0.508)
			(layers "F.Cu" "F.Mask" "F.Paste")
			(net "GND")
		)
	)
	(footprint ""
		(layer "F.Cu")
		(at 13.429234 -326.145652 180)
		(property "Reference" "R145"
			(at -1.184148 -0.042164 0)
			(unlocked yes)
			(layer "F.SilkS")
			(effects
				(font
					(size 0.7874 0.5842)
					(thickness 0.1524)
				)
				(justify left)
			)
		)
		(property "Value" ""
			(at 0 0 180)
			(layer "F.Fab")
			(effects
				(font
					(size 1.27 1.27)
				)
			)
		)
		(duplicate_pad_numbers_are_jumpers no)
		(fp_line
			(start 0.7874 0.4064)
			(end -0.7874 0.4064)
			(stroke
				(width 0.1524)
				(type default)
			)
			(layer "F.SilkS")
		)
		(fp_line
			(start 0.7874 -0.4064)
			(end 0.7874 0.4064)
			(stroke
				(width 0.1524)
				(type default)
			)
			(layer "F.SilkS")
		)
		(fp_line
			(start -0.7874 0.4064)
			(end -0.7874 -0.4064)
			(stroke
				(width 0.1524)
				(type default)
			)
			(layer "F.SilkS")
		)
		(fp_line
			(start -0.7874 -0.4064)
			(end 0.7874 -0.4064)
			(stroke
				(width 0.1524)
				(type default)
			)
			(layer "F.SilkS")
		)
		(fp_poly
			(pts
				(xy -0.508 0.2794) (xy -0.508 0.2286) (xy -0.635 0.2286) (xy -0.635 -0.254) (xy -0.5334 -0.254)
				(xy -0.5334 -0.2794) (xy 0.5334 -0.2794) (xy 0.5334 -0.254) (xy 0.635 -0.254) (xy 0.635 0.254) (xy 0.5334 0.254)
				(xy 0.5334 0.2794)
			)
			(stroke
				(width 0)
				(type default)
			)
			(fill no)
			(layer "F.CrtYd")
		)
		(pad "1" smd rect
			(at 0.40005 0 180)
			(size 0.4572 0.508)
			(layers "F.Cu" "F.Mask" "F.Paste")
			(net "FAN4_TACH")
		)
		(pad "2" smd rect
			(at -0.40005 0 180)
			(size 0.4572 0.508)
			(layers "F.Cu" "F.Mask" "F.Paste")
			(net "P12V")
		)
	)
	(footprint ""
		(layer "F.Cu")
		(at 50.083466 -482.70668 180)
		(property "Reference" "CE21"
			(at -4.321048 2.407666 0)
			(unlocked yes)
			(layer "F.SilkS")
			(effects
				(font
					(size 0.7874 0.5842)
					(thickness 0.1524)
				)
				(justify left)
			)
		)
		(property "Value" ""
			(at 0 0 180)
			(layer "F.Fab")
			(effects
				(font
					(size 1.27 1.27)
				)
			)
		)
		(duplicate_pad_numbers_are_jumpers no)
		(fp_line
			(start 0 -4.2672)
			(end 0 4.2672)
			(stroke
				(width 0.1524)
				(type default)
			)
			(layer "F.SilkS")
		)
		(fp_circle
			(center 0 0)
			(end -4.2672 0)
			(stroke
				(width 0.1524)
				(type default)
			)
			(fill no)
			(layer "F.SilkS")
		)
		(fp_poly
			(pts
				(arc
					(start 0 -4.2672)
					(mid 4.2672 0)
					(end 0 4.2672)
				)
			)
			(stroke
				(width 0)
				(type default)
			)
			(fill yes)
			(layer "F.SilkS")
		)
		(fp_poly
			(pts
				(xy -2.5146 -0.762) (xy -0.9906 -0.762) (xy -0.9906 0.762) (xy -2.5146 0.762)
			)
			(stroke
				(width 0)
				(type default)
			)
			(fill no)
			(layer "B.CrtYd")
		)
		(fp_poly
			(pts
				(arc
					(start 1.7526 0.762)
					(mid 2.291415 -0.538815)
					(end 0.9906 0)
				)
				(arc
					(start 0.9906 0.0254)
					(mid 1.206345 0.546255)
					(end 1.7272 0.762)
				)
			)
			(stroke
				(width 0)
				(type default)
			)
			(fill no)
			(layer "B.CrtYd")
		)
		(fp_poly
			(pts
				(arc
					(start -4.2672 0)
					(mid 4.2672 0)
					(end -4.2672 0)
				)
			)
			(stroke
				(width 0)
				(type default)
			)
			(fill no)
			(layer "F.CrtYd")
		)
		(fp_circle
			(center 0 0)
			(end -4.2672 0)
			(stroke
				(width 0.1)
				(type default)
			)
			(fill no)
			(layer "F.Fab")
		)
		(fp_text user "+"
			(at -5.247386 0.635 180)
			(unlocked yes)
			(layer "F.SilkS")
			(effects
				(font
					(size 0.7874 0.5842)
					(thickness 0.1524)
				)
				(justify left)
			)
		)
		(fp_text user "+"
			(at -5.6642 -0.34925 180)
			(unlocked yes)
			(layer "F.Fab")
			(effects
				(font
					(size 1.905 1.4224)
					(thickness 0.000001)
				)
				(justify left)
			)
		)
		(pad "1" thru_hole rect
			(at -1.75006 0 180)
			(size 1.397 1.397)
			(drill 0.9144)
			(layers "*.Cu" "*.Mask")
			(remove_unused_layers no)
			(net "P12V")
			(clearance 0.0127)
			(thermal_gap 0.0127)
			(padstack
				(mode front_inner_back)
				(layer "Inner"
					(shape circle)
					(size 1.397 1.397)
					(clearance 0.0127)
				)
				(layer "B.Cu"
					(shape rect)
					(size 1.397 1.397)
					(clearance 0.0127)
				)
			)
		)
		(pad "2" thru_hole circle
			(at 1.75006 0 180)
			(size 1.397 1.397)
			(drill 0.9144)
			(layers "*.Cu" "*.Mask")
			(remove_unused_layers no)
			(net "GND")
			(clearance 0.0127)
			(thermal_gap 0.0127)
		)
	)
	(footprint ""
		(layer "F.Cu")
		(at 26.25217 -454.646538 180)
		(property "Reference" "R54"
			(at 3.704336 0.165608 0)
			(unlocked yes)
			(layer "F.SilkS")
			(effects
				(font
					(size 0.7874 0.5842)
					(thickness 0.1524)
				)
				(justify left)
			)
		)
		(property "Value" ""
			(at 0 0 180)
			(layer "F.Fab")
			(effects
				(font
					(size 1.27 1.27)
				)
			)
		)
		(duplicate_pad_numbers_are_jumpers no)
		(fp_line
			(start 0.7874 0.4064)
			(end -0.7874 0.4064)
			(stroke
				(width 0.1524)
				(type default)
			)
			(layer "F.SilkS")
		)
		(fp_line
			(start 0.7874 -0.4064)
			(end 0.7874 0.4064)
			(stroke
				(width 0.1524)
				(type default)
			)
			(layer "F.SilkS")
		)
		(fp_line
			(start -0.7874 0.4064)
			(end -0.7874 -0.4064)
			(stroke
				(width 0.1524)
				(type default)
			)
			(layer "F.SilkS")
		)
		(fp_line
			(start -0.7874 -0.4064)
			(end 0.7874 -0.4064)
			(stroke
				(width 0.1524)
				(type default)
			)
			(layer "F.SilkS")
		)
		(fp_poly
			(pts
				(xy -0.508 0.2794) (xy -0.508 0.2286) (xy -0.635 0.2286) (xy -0.635 -0.254) (xy -0.5334 -0.254)
				(xy -0.5334 -0.2794) (xy 0.5334 -0.2794) (xy 0.5334 -0.254) (xy 0.635 -0.254) (xy 0.635 0.254) (xy 0.5334 0.254)
				(xy 0.5334 0.2794)
			)
			(stroke
				(width 0)
				(type default)
			)
			(fill no)
			(layer "F.CrtYd")
		)
		(pad "1" smd rect
			(at 0.40005 0 180)
			(size 0.4572 0.508)
			(layers "F.Cu" "F.Mask" "F.Paste")
			(net "GND")
		)
		(pad "2" smd rect
			(at -0.40005 0 180)
			(size 0.4572 0.508)
			(layers "F.Cu" "F.Mask" "F.Paste")
			(net "PSU6_PS_ON_N")
		)
	)
	(footprint ""
		(layer "F.Cu")
		(at 39.979854 -375.988326 180)
		(property "Reference" "R14"
			(at -2.032762 0.011938 0)
			(unlocked yes)
			(layer "F.SilkS")
			(effects
				(font
					(size 0.7874 0.5842)
					(thickness 0.1524)
				)
				(justify left)
			)
		)
		(property "Value" ""
			(at 0 0 180)
			(layer "F.Fab")
			(effects
				(font
					(size 1.27 1.27)
				)
			)
		)
		(duplicate_pad_numbers_are_jumpers no)
		(fp_line
			(start 0.7874 0.4064)
			(end -0.7874 0.4064)
			(stroke
				(width 0.1524)
				(type default)
			)
			(layer "F.SilkS")
		)
		(fp_line
			(start 0.7874 -0.4064)
			(end 0.7874 0.4064)
			(stroke
				(width 0.1524)
				(type default)
			)
			(layer "F.SilkS")
		)
		(fp_line
			(start -0.7874 0.4064)
			(end -0.7874 -0.4064)
			(stroke
				(width 0.1524)
				(type default)
			)
			(layer "F.SilkS")
		)
		(fp_line
			(start -0.7874 -0.4064)
			(end 0.7874 -0.4064)
			(stroke
				(width 0.1524)
				(type default)
			)
			(layer "F.SilkS")
		)
		(fp_poly
			(pts
				(xy -0.508 0.2794) (xy -0.508 0.2286) (xy -0.635 0.2286) (xy -0.635 -0.254) (xy -0.5334 -0.254)
				(xy -0.5334 -0.2794) (xy 0.5334 -0.2794) (xy 0.5334 -0.254) (xy 0.635 -0.254) (xy 0.635 0.254) (xy 0.5334 0.254)
				(xy 0.5334 0.2794)
			)
			(stroke
				(width 0)
				(type default)
			)
			(fill no)
			(layer "F.CrtYd")
		)
		(pad "1" smd rect
			(at 0.40005 0 180)
			(size 0.4572 0.508)
			(layers "F.Cu" "F.Mask" "F.Paste")
			(net "PSU5_REMOTE_P")
		)
		(pad "2" smd rect
			(at -0.40005 0 180)
			(size 0.4572 0.508)
			(layers "F.Cu" "F.Mask" "F.Paste")
			(net "P12V")
		)
	)
	(footprint ""
		(layer "F.Cu")
		(at 72.478392 -149.621748 -90)
		(property "Reference" "C22"
			(at -3.210052 -0.035814 90)
			(unlocked yes)
			(layer "F.SilkS")
			(effects
				(font
					(size 0.7874 0.5842)
					(thickness 0.1524)
				)
			)
		)
		(property "Value" ""
			(at 0 0 270)
			(layer "F.Fab")
			(effects
				(font
					(size 1.27 1.27)
				)
			)
		)
		(duplicate_pad_numbers_are_jumpers no)
		(fp_line
			(start -1.2954 0.5842)
			(end -1.2954 -0.5842)
			(stroke
				(width 0.1524)
				(type default)
			)
			(layer "F.SilkS")
		)
		(fp_line
			(start 1.2954 0.5842)
			(end -1.2954 0.5842)
			(stroke
				(width 0.1524)
				(type default)
			)
			(layer "F.SilkS")
		)
		(fp_line
			(start -1.2954 -0.5842)
			(end 1.2954 -0.5842)
			(stroke
				(width 0.1524)
				(type default)
			)
			(layer "F.SilkS")
		)
		(fp_line
			(start 0 -0.5842)
			(end 0 0.5842)
			(stroke
				(width 0.1524)
				(type default)
			)
			(layer "F.SilkS")
		)
		(fp_line
			(start 1.2954 -0.5842)
			(end 1.2954 0.5842)
			(stroke
				(width 0.1524)
				(type default)
			)
			(layer "F.SilkS")
		)
		(fp_poly
			(pts
				(xy 0.8636 -0.4572) (xy 0.8636 -0.3556) (xy 1.143 -0.3556) (xy 1.143 0.3556) (xy 0.8636 0.3556)
				(xy 0.8636 0.4572) (xy -0.8636 0.4572) (xy -0.8636 0.3556) (xy -1.143 0.3556) (xy -1.143 -0.3556)
				(xy -0.8636 -0.3556) (xy -0.8636 -0.4572)
			)
			(stroke
				(width 0)
				(type default)
			)
			(fill no)
			(layer "F.CrtYd")
		)
		(fp_line
			(start -0.884936 0.504952)
			(end -0.884936 -0.504952)
			(stroke
				(width 0.1)
				(type default)
			)
			(layer "F.Fab")
		)
		(fp_line
			(start 0.884936 0.504952)
			(end -0.884936 0.504952)
			(stroke
				(width 0.1)
				(type default)
			)
			(layer "F.Fab")
		)
		(fp_line
			(start -0.884936 -0.504952)
			(end 0.884936 -0.504952)
			(stroke
				(width 0.1)
				(type default)
			)
			(layer "F.Fab")
		)
		(fp_line
			(start 0.884936 -0.504952)
			(end 0.884936 0.504952)
			(stroke
				(width 0.1)
				(type default)
			)
			(layer "F.Fab")
		)
		(pad "1" smd rect
			(at 0.7366 0)
			(size 0.7112 0.8128)
			(layers "F.Cu" "F.Mask" "F.Paste")
			(net "P12V")
		)
		(pad "2" smd rect
			(at -0.7366 0)
			(size 0.7112 0.8128)
			(layers "F.Cu" "F.Mask" "F.Paste")
			(net "GND")
		)
	)
	(footprint ""
		(layer "F.Cu")
		(at 25.857708 -363.01553)
		(property "Reference" "R80"
			(at -3.917442 -0.225298 0)
			(unlocked yes)
			(layer "F.SilkS")
			(effects
				(font
					(size 0.7874 0.5842)
					(thickness 0.1524)
				)
				(justify left)
			)
		)
		(property "Value" ""
			(at 0 0 0)
			(layer "F.Fab")
			(effects
				(font
					(size 1.27 1.27)
				)
			)
		)
		(duplicate_pad_numbers_are_jumpers no)
		(fp_line
			(start -0.7874 -0.4064)
			(end 0.7874 -0.4064)
			(stroke
				(width 0.1524)
				(type default)
			)
			(layer "F.SilkS")
		)
		(fp_line
			(start -0.7874 0.4064)
			(end -0.7874 -0.4064)
			(stroke
				(width 0.1524)
				(type default)
			)
			(layer "F.SilkS")
		)
		(fp_line
			(start 0.7874 -0.4064)
			(end 0.7874 0.4064)
			(stroke
				(width 0.1524)
				(type default)
			)
			(layer "F.SilkS")
		)
		(fp_line
			(start 0.7874 0.4064)
			(end -0.7874 0.4064)
			(stroke
				(width 0.1524)
				(type default)
			)
			(layer "F.SilkS")
		)
		(fp_poly
			(pts
				(xy -0.508 0.2794) (xy -0.508 0.2286) (xy -0.635 0.2286) (xy -0.635 -0.254) (xy -0.5334 -0.254)
				(xy -0.5334 -0.2794) (xy 0.5334 -0.2794) (xy 0.5334 -0.254) (xy 0.635 -0.254) (xy 0.635 0.254) (xy 0.5334 0.254)
				(xy 0.5334 0.2794)
			)
			(stroke
				(width 0)
				(type default)
			)
			(fill no)
			(layer "F.CrtYd")
		)
		(pad "1" smd rect
			(at 0.40005 0)
			(size 0.4572 0.508)
			(layers "F.Cu" "F.Mask" "F.Paste")
			(net "PSU5_RESET")
		)
		(pad "2" smd rect
			(at -0.40005 0)
			(size 0.4572 0.508)
			(layers "F.Cu" "F.Mask" "F.Paste")
			(net "P12V_STBY")
		)
	)
	(footprint ""
		(layer "F.Cu")
		(at 39.653718 -283.096208 -90)
		(property "Reference" "R16"
			(at 0.95885 -2.95783 90)
			(unlocked yes)
			(layer "F.SilkS")
			(effects
				(font
					(size 0.7874 0.5842)
					(thickness 0.1524)
				)
				(justify left)
			)
		)
		(property "Value" ""
			(at 0 0 270)
			(layer "F.Fab")
			(effects
				(font
					(size 1.27 1.27)
				)
			)
		)
		(duplicate_pad_numbers_are_jumpers no)
		(fp_line
			(start -0.7874 0.4064)
			(end -0.7874 -0.4064)
			(stroke
				(width 0.1524)
				(type default)
			)
			(layer "F.SilkS")
		)
		(fp_line
			(start 0.7874 0.4064)
			(end -0.7874 0.4064)
			(stroke
				(width 0.1524)
				(type default)
			)
			(layer "F.SilkS")
		)
		(fp_line
			(start -0.7874 -0.4064)
			(end 0.7874 -0.4064)
			(stroke
				(width 0.1524)
				(type default)
			)
			(layer "F.SilkS")
		)
		(fp_line
			(start 0.7874 -0.4064)
			(end 0.7874 0.4064)
			(stroke
				(width 0.1524)
				(type default)
			)
			(layer "F.SilkS")
		)
		(fp_poly
			(pts
				(xy -0.508 0.2794) (xy -0.508 0.2286) (xy -0.635 0.2286) (xy -0.635 -0.254) (xy -0.5334 -0.254)
				(xy -0.5334 -0.2794) (xy 0.5334 -0.2794) (xy 0.5334 -0.254) (xy 0.635 -0.254) (xy 0.635 0.254) (xy 0.5334 0.254)
				(xy 0.5334 0.2794)
			)
			(stroke
				(width 0)
				(type default)
			)
			(fill no)
			(layer "F.CrtYd")
		)
		(pad "1" smd rect
			(at 0.40005 0 270)
			(size 0.4572 0.508)
			(layers "F.Cu" "F.Mask" "F.Paste")
			(net "PSU4_AD0")
		)
		(pad "2" smd rect
			(at -0.40005 0 270)
			(size 0.4572 0.508)
			(layers "F.Cu" "F.Mask" "F.Paste")
			(net "P12V_STBY")
		)
	)
	(footprint ""
		(layer "F.Cu")
		(at 40.11422 -371.513354 180)
		(property "Reference" "R27"
			(at -1.756918 -0.348742 0)
			(unlocked yes)
			(layer "F.SilkS")
			(effects
				(font
					(size 0.7874 0.5842)
					(thickness 0.1524)
				)
				(justify left)
			)
		)
		(property "Value" ""
			(at 0 0 180)
			(layer "F.Fab")
			(effects
				(font
					(size 1.27 1.27)
				)
			)
		)
		(duplicate_pad_numbers_are_jumpers no)
		(fp_line
			(start 0.7874 0.4064)
			(end -0.7874 0.4064)
			(stroke
				(width 0.1524)
				(type default)
			)
			(layer "F.SilkS")
		)
		(fp_line
			(start 0.7874 -0.4064)
			(end 0.7874 0.4064)
			(stroke
				(width 0.1524)
				(type default)
			)
			(layer "F.SilkS")
		)
		(fp_line
			(start -0.7874 0.4064)
			(end -0.7874 -0.4064)
			(stroke
				(width 0.1524)
				(type default)
			)
			(layer "F.SilkS")
		)
		(fp_line
			(start -0.7874 -0.4064)
			(end 0.7874 -0.4064)
			(stroke
				(width 0.1524)
				(type default)
			)
			(layer "F.SilkS")
		)
		(fp_poly
			(pts
				(xy -0.508 0.2794) (xy -0.508 0.2286) (xy -0.635 0.2286) (xy -0.635 -0.254) (xy -0.5334 -0.254)
				(xy -0.5334 -0.2794) (xy 0.5334 -0.2794) (xy 0.5334 -0.254) (xy 0.635 -0.254) (xy 0.635 0.254) (xy 0.5334 0.254)
				(xy 0.5334 0.2794)
			)
			(stroke
				(width 0)
				(type default)
			)
			(fill no)
			(layer "F.CrtYd")
		)
		(pad "1" smd rect
			(at 0.40005 0 180)
			(size 0.4572 0.508)
			(layers "F.Cu" "F.Mask" "F.Paste")
			(net "PSU5_AD0")
		)
		(pad "2" smd rect
			(at -0.40005 0 180)
			(size 0.4572 0.508)
			(layers "F.Cu" "F.Mask" "F.Paste")
			(net "GND")
		)
	)
)
